FILE_TYPE = CONNECTIVITY;
{Allegro Design Entry HDL 16.6-p007 (v16-6-112F) 10/10/2012}
"PAGE_NUMBER" = 117;
0"NC";
1"DMI_CPU0_PCH_TX_C_DP<3:0>";
2"DMI_CPU0_PCH_RX_DN<3:0>";
3"DMI_CPU0_PCH_RX_DP<3:0>";
4"P3E_CPU0_PE1_PCH_TXN<7:0>";
5"P3E_CPU0_PE1_PCH_TXP<7:0>";
6"P3E_CPU0_PE1_PCH_C_TXP<15:8>";
7"P3E_CPU0_PE1_PCH_C_TXN<15:8>";
8"DMI_CPU0_PCH_TX_C_DN<3:0>";
9"P3E_CPU0_PE1_PCH_RXN<7:0>";
10"P3E_CPU0_PE1_PCH_RXP<7:0>";
11"P3E_CPU0_PE1_PCH_R_RXN<15:8>";
12"P3E_CPU0_PE1_PCH_R_RXP<15:8>";
13"DMI_CPU0_PCH_TX_C_DN<1>";
14"DMI_CPU0_PCH_TX_C_DN<2>";
15"P3E_CPU0_PE1_PCH_R_RXP<9>";
16"P3E_CPU0_PE1_PCH_R_RXN<9>";
17"P3E_CPU0_PE1_PCH_R_RXP<15>";
18"P3E_CPU0_PE1_PCH_R_RXN<15>";
19"P3E_CPU0_PE1_PCH_R_RXP<14>";
20"P3E_CPU0_PE1_PCH_R_RXN<14>";
21"P3E_CPU0_PE1_PCH_R_RXP<13>";
22"P3E_CPU0_PE1_PCH_R_RXN<13>";
23"P3E_CPU0_PE1_PCH_R_RXP<12>";
24"P3E_CPU0_PE1_PCH_R_RXN<12>";
25"P3E_CPU0_PE1_PCH_R_RXP<11>";
26"P3E_CPU0_PE1_PCH_R_RXN<11>";
27"P3E_CPU0_PE1_PCH_R_RXP<10>";
28"P3E_CPU0_PE1_PCH_R_RXN<10>";
29"DMI_CPU0_PCH_RX_DP<1>";
30"DMI_CPU0_PCH_RX_DP<2>";
31"DMI_CPU0_PCH_RX_DP<3>";
32"DMI_CPU0_PCH_RX_DN<0>";
33"DMI_CPU0_PCH_RX_DN<1>";
34"DMI_CPU0_PCH_RX_DN<2>";
35"P3E_CPU0_PE1_PCH_R_RXP<8>";
36"P3E_CPU0_PE1_PCH_R_RXN<8>";
37"P3E_CPU0_PE1_PCH_RXP<7>";
38"P3E_CPU0_PE1_PCH_RXN<7>";
39"P3E_CPU0_PE1_PCH_RXP<6>";
40"P3E_CPU0_PE1_PCH_RXN<6>";
41"P3E_CPU0_PE1_PCH_RXP<5>";
42"P3E_CPU0_PE1_PCH_RXN<5>";
43"P3E_CPU0_PE1_PCH_RXP<4>";
44"P3E_CPU0_PE1_PCH_RXN<4>";
45"P3E_CPU0_PE1_PCH_RXP<3>";
46"P3E_CPU0_PE1_PCH_RXN<3>";
47"P3E_CPU0_PE1_PCH_RXP<2>";
48"P3E_CPU0_PE1_PCH_RXN<2>";
49"P3E_CPU0_PE1_PCH_RXP<1>";
50"P3E_CPU0_PE1_PCH_RXN<1>";
51"P3E_CPU0_PE1_PCH_RXP<0>";
52"P3E_CPU0_PE1_PCH_RXN<0>";
53"P3E_CPU0_PE1_PCH_C_TXN<9>";
54"P3E_CPU0_PE1_PCH_C_TXP<9>";
55"P3E_CPU0_PE1_PCH_C_TXN<15>";
56"P3E_CPU0_PE1_PCH_C_TXP<15>";
57"P3E_CPU0_PE1_PCH_C_TXN<14>";
58"P3E_CPU0_PE1_PCH_C_TXP<14>";
59"P3E_CPU0_PE1_PCH_C_TXN<13>";
60"P3E_CPU0_PE1_PCH_C_TXP<13>";
61"P3E_CPU0_PE1_PCH_C_TXN<12>";
62"P3E_CPU0_PE1_PCH_C_TXP<12>";
63"P3E_CPU0_PE1_PCH_C_TXP<11>";
64"P3E_CPU0_PE1_PCH_C_TXN<11>";
65"P3E_CPU0_PE1_PCH_C_TXN<10>";
66"P3E_CPU0_PE1_PCH_C_TXP<10>";
67"DMI_CPU0_PCH_TX_C_DP<0>";
68"DMI_CPU0_PCH_TX_C_DP<2>";
69"DMI_CPU0_PCH_TX_C_DP<3>";
70"DMI_CPU0_PCH_TX_C_DN<0>";
71"DMI_CPU0_PCH_TX_C_DN<3>";
72"P3E_CPU0_PE1_PCH_C_TXN<8>";
73"P3E_CPU0_PE1_PCH_C_TXP<8>";
74"P3E_CPU0_PE1_PCH_TXP<7>";
75"P3E_CPU0_PE1_PCH_TXN<7>";
76"P3E_CPU0_PE1_PCH_TXP<6>";
77"P3E_CPU0_PE1_PCH_TXN<6>";
78"P3E_CPU0_PE1_PCH_TXP<5>";
79"P3E_CPU0_PE1_PCH_TXN<5>";
80"P3E_CPU0_PE1_PCH_TXP<4>";
81"P3E_CPU0_PE1_PCH_TXN<4>";
82"P3E_CPU0_PE1_PCH_TXP<3>";
83"P3E_CPU0_PE1_PCH_TXN<3>";
84"P3E_CPU0_PE1_PCH_TXP<2>";
85"P3E_CPU0_PE1_PCH_TXN<2>";
86"P3E_CPU0_PE1_PCH_TXP<1>";
87"P3E_CPU0_PE1_PCH_TXN<1>";
88"P3E_CPU0_PE1_PCH_TXP<0>";
89"P3E_CPU0_PE1_PCH_TXN<0>";
90"DMI_CPU0_PCH_RX_DP<0>";
91"DMI_CPU0_PCH_RX_DN<3>";
92"DMI_CPU0_PCH_TX_C_DP<1>";
%"TAP"
"6","(-5500,2400)","0","mstr_standard","I101";
;
CDS_LIB"mstr_standard"
BODY_TYPE"PLUMBING"
HDL_TAP"TRUE";
"B \NAC \NWC"7;
"S \NAC"
BN"12"61;
%"TAP"
"6","(-5500,2500)","0","mstr_standard","I102";
;
CDS_LIB"mstr_standard"
BODY_TYPE"PLUMBING"
HDL_TAP"TRUE";
"B \NAC \NWC"7;
"S \NAC"
BN"13"59;
%"TAP"
"6","(-5500,2600)","0","mstr_standard","I103";
;
CDS_LIB"mstr_standard"
BODY_TYPE"PLUMBING"
HDL_TAP"TRUE";
"B \NAC \NWC"7;
"S \NAC"
BN"14"57;
%"TAP"
"6","(-5500,2700)","0","mstr_standard","I104";
;
CDS_LIB"mstr_standard"
BODY_TYPE"PLUMBING"
HDL_TAP"TRUE";
"B \NAC \NWC"7;
"S \NAC"
BN"15"55;
%"TAP"
"6","(-5625,1950)","0","mstr_standard","I105";
;
CDS_LIB"mstr_standard"
BODY_TYPE"PLUMBING"
HDL_TAP"TRUE";
"B \NAC \NWC"6;
"S \NAC"
BN"8"73;
%"TAP"
"6","(-5625,2050)","0","mstr_standard","I106";
;
CDS_LIB"mstr_standard"
BODY_TYPE"PLUMBING"
HDL_TAP"TRUE";
"B \NAC \NWC"6;
"S \NAC"
BN"9"54;
%"TAP"
"6","(-5625,2150)","0","mstr_standard","I107";
;
CDS_LIB"mstr_standard"
BODY_TYPE"PLUMBING"
HDL_TAP"TRUE";
"B \NAC \NWC"6;
"S \NAC"
BN"10"66;
%"TAP"
"6","(-5625,2350)","0","mstr_standard","I109";
;
CDS_LIB"mstr_standard"
BODY_TYPE"PLUMBING"
HDL_TAP"TRUE";
"B \NAC \NWC"6;
"S \NAC"
BN"12"62;
%"TAP"
"6","(-5625,2450)","0","mstr_standard","I110";
;
CDS_LIB"mstr_standard"
BODY_TYPE"PLUMBING"
HDL_TAP"TRUE";
"B \NAC \NWC"6;
"S \NAC"
BN"13"60;
%"TAP"
"6","(-5625,2550)","0","mstr_standard","I111";
;
CDS_LIB"mstr_standard"
BODY_TYPE"PLUMBING"
HDL_TAP"TRUE";
"B \NAC \NWC"6;
"S \NAC"
BN"14"58;
%"TAP"
"6","(-5625,2650)","0","mstr_standard","I112";
;
CDS_LIB"mstr_standard"
BODY_TYPE"PLUMBING"
HDL_TAP"TRUE";
"B \NAC \NWC"6;
"S \NAC"
BN"15"56;
%"TAP"
"1","(-2600,1950)","0","mstr_standard","I113";
;
CDS_LIB"mstr_standard"
BODY_TYPE"PLUMBING"
HDL_TAP"TRUE";
"B \NAC \NWC"11;
"S \NAC"
BN"8"36;
%"TAP"
"1","(-2600,2050)","0","mstr_standard","I114";
;
CDS_LIB"mstr_standard"
BODY_TYPE"PLUMBING"
HDL_TAP"TRUE";
"B \NAC \NWC"11;
"S \NAC"
BN"9"16;
%"TAP"
"1","(-2600,2150)","0","mstr_standard","I115";
;
CDS_LIB"mstr_standard"
BODY_TYPE"PLUMBING"
HDL_TAP"TRUE";
"B \NAC \NWC"11;
"S \NAC"
BN"10"28;
%"TAP"
"1","(-2600,2250)","0","mstr_standard","I116";
;
CDS_LIB"mstr_standard"
BODY_TYPE"PLUMBING"
HDL_TAP"TRUE";
"B \NAC \NWC"11;
"S \NAC"
BN"11"26;
%"TAP"
"1","(-2600,2350)","0","mstr_standard","I117";
;
CDS_LIB"mstr_standard"
BODY_TYPE"PLUMBING"
HDL_TAP"TRUE";
"B \NAC \NWC"11;
"S \NAC"
BN"12"24;
%"TAP"
"1","(-2600,2450)","0","mstr_standard","I118";
;
CDS_LIB"mstr_standard"
BODY_TYPE"PLUMBING"
HDL_TAP"TRUE";
"B \NAC \NWC"11;
"S \NAC"
BN"13"22;
%"TAP"
"1","(-2600,2550)","0","mstr_standard","I119";
;
CDS_LIB"mstr_standard"
BODY_TYPE"PLUMBING"
HDL_TAP"TRUE";
"B \NAC \NWC"11;
"S \NAC"
BN"14"20;
%"TAP"
"1","(-2600,2650)","0","mstr_standard","I120";
;
CDS_LIB"mstr_standard"
BODY_TYPE"PLUMBING"
HDL_TAP"TRUE";
"B \NAC \NWC"11;
"S \NAC"
BN"15"18;
%"TAP"
"1","(-2725,2000)","0","mstr_standard","I121";
;
CDS_LIB"mstr_standard"
BODY_TYPE"PLUMBING"
HDL_TAP"TRUE";
"B \NAC \NWC"12;
"S \NAC"
BN"8"35;
%"TAP"
"1","(-2725,2100)","0","mstr_standard","I122";
;
CDS_LIB"mstr_standard"
BODY_TYPE"PLUMBING"
HDL_TAP"TRUE";
"B \NAC \NWC"12;
"S \NAC"
BN"9"15;
%"TAP"
"1","(-2725,2200)","0","mstr_standard","I123";
;
CDS_LIB"mstr_standard"
BODY_TYPE"PLUMBING"
HDL_TAP"TRUE";
"B \NAC \NWC"12;
"S \NAC"
BN"10"27;
%"TAP"
"1","(-2725,2300)","0","mstr_standard","I124";
;
CDS_LIB"mstr_standard"
BODY_TYPE"PLUMBING"
HDL_TAP"TRUE";
"B \NAC \NWC"12;
"S \NAC"
BN"11"25;
%"TAP"
"1","(-2725,2400)","0","mstr_standard","I125";
;
CDS_LIB"mstr_standard"
BODY_TYPE"PLUMBING"
HDL_TAP"TRUE";
"B \NAC \NWC"12;
"S \NAC"
BN"12"23;
%"TAP"
"1","(-2725,2500)","0","mstr_standard","I126";
;
CDS_LIB"mstr_standard"
BODY_TYPE"PLUMBING"
HDL_TAP"TRUE";
"B \NAC \NWC"12;
"S \NAC"
BN"13"21;
%"TAP"
"1","(-2725,2600)","0","mstr_standard","I127";
;
CDS_LIB"mstr_standard"
BODY_TYPE"PLUMBING"
HDL_TAP"TRUE";
"B \NAC \NWC"12;
"S \NAC"
BN"14"19;
%"TAP"
"1","(-2725,2700)","0","mstr_standard","I128";
;
CDS_LIB"mstr_standard"
BODY_TYPE"PLUMBING"
HDL_TAP"TRUE";
"B \NAC \NWC"12;
"S \NAC"
BN"15"17;
%"TAP"
"6","(-5625,2300)","0","mstr_standard","I133";
;
CDS_LIB"mstr_standard"
BODY_TYPE"PLUMBING"
HDL_TAP"TRUE";
"B \NAC \NWC"6;
"S \NAC"
BN"11"63;
%"TAP"
"6","(-5500,2250)","0","mstr_standard","I134";
;
CDS_LIB"mstr_standard"
BODY_TYPE"PLUMBING"
HDL_TAP"TRUE";
"B \NAC \NWC"7;
"S \NAC"
BN"11"64;
%"TAP"
"1","(-5425,3150)","2","mstr_standard","I21";
;
BOM_COST"SB"
CDS_LIB"mstr_standard"
BODY_TYPE"PLUMBING"
HDL_TAP"TRUE";
"B \NAC \NWC"1;
"S \NAC"
BN"3"69;
%"TAP"
"1","(-5425,3050)","2","mstr_standard","I22";
;
BOM_COST"SB"
CDS_LIB"mstr_standard"
BODY_TYPE"PLUMBING"
HDL_TAP"TRUE";
"B \NAC \NWC"1;
"S \NAC"
BN"2"68;
%"TAP"
"1","(-5425,2950)","2","mstr_standard","I23";
;
CDS_LIB"mstr_standard"
BOM_COST"SB"
BODY_TYPE"PLUMBING"
HDL_TAP"TRUE";
"B \NAC \NWC"1;
"S \NAC"
BN"1"92;
%"TAP"
"1","(-5425,2850)","2","mstr_standard","I24";
;
CDS_LIB"mstr_standard"
BOM_COST"SB"
BODY_TYPE"PLUMBING"
HDL_TAP"TRUE";
"B \NAC \NWC"1;
"S \NAC"
BN"0"67;
%"TAP"
"1","(-5575,3100)","2","mstr_standard","I25";
;
BOM_COST"SB"
CDS_LIB"mstr_standard"
BODY_TYPE"PLUMBING"
HDL_TAP"TRUE";
"B \NAC \NWC"8;
"S \NAC"
BN"3"71;
%"TAP"
"1","(-5575,3000)","2","mstr_standard","I26";
;
BOM_COST"SB"
CDS_LIB"mstr_standard"
BODY_TYPE"PLUMBING"
HDL_TAP"TRUE";
"B \NAC \NWC"8;
"S \NAC"
BN"2"14;
%"TAP"
"1","(-5575,2900)","2","mstr_standard","I27";
;
BOM_COST"SB"
CDS_LIB"mstr_standard"
BODY_TYPE"PLUMBING"
HDL_TAP"TRUE";
"B \NAC \NWC"8;
"S \NAC"
BN"1"13;
%"TAP"
"1","(-5575,2800)","2","mstr_standard","I28";
;
BOM_COST"SB"
CDS_LIB"mstr_standard"
BODY_TYPE"PLUMBING"
HDL_TAP"TRUE";
"B \NAC \NWC"8;
"S \NAC"
BN"0"70;
%"TAP"
"6","(-2725,3150)","2","mstr_standard","I29";
;
BOM_COST"SB"
CDS_LIB"mstr_standard"
BODY_TYPE"PLUMBING"
HDL_TAP"TRUE";
"B \NAC \NWC"3;
"S \NAC"
BN"3"31;
%"TAP"
"6","(-2600,3100)","2","mstr_standard","I30";
;
BOM_COST"SB"
CDS_LIB"mstr_standard"
BODY_TYPE"PLUMBING"
HDL_TAP"TRUE";
"B \NAC \NWC"2;
"S \NAC"
BN"3"91;
%"TAP"
"6","(-2725,3050)","2","mstr_standard","I31";
;
BOM_COST"SB"
CDS_LIB"mstr_standard"
BODY_TYPE"PLUMBING"
HDL_TAP"TRUE";
"B \NAC \NWC"3;
"S \NAC"
BN"2"30;
%"TAP"
"6","(-2725,2950)","2","mstr_standard","I32";
;
BOM_COST"SB"
CDS_LIB"mstr_standard"
BODY_TYPE"PLUMBING"
HDL_TAP"TRUE";
"B \NAC \NWC"3;
"S \NAC"
BN"1"29;
%"TAP"
"6","(-2725,2850)","2","mstr_standard","I33";
;
CDS_LIB"mstr_standard"
BOM_COST"SB"
BODY_TYPE"PLUMBING"
HDL_TAP"TRUE";
"B \NAC \NWC"3;
"S \NAC"
BN"0"90;
%"TAP"
"6","(-2600,3000)","2","mstr_standard","I34";
;
BOM_COST"SB"
CDS_LIB"mstr_standard"
BODY_TYPE"PLUMBING"
HDL_TAP"TRUE";
"B \NAC \NWC"2;
"S \NAC"
BN"2"34;
%"TAP"
"6","(-2600,2900)","2","mstr_standard","I35";
;
BOM_COST"SB"
CDS_LIB"mstr_standard"
BODY_TYPE"PLUMBING"
HDL_TAP"TRUE";
"B \NAC \NWC"2;
"S \NAC"
BN"1"33;
%"TAP"
"6","(-2600,2800)","2","mstr_standard","I36";
;
CDS_LIB"mstr_standard"
BOM_COST"SB"
BODY_TYPE"PLUMBING"
HDL_TAP"TRUE";
"B \NAC \NWC"2;
"S \NAC"
BN"0"32;
%"TAP"
"6","(-5625,1150)","0","mstr_standard","I42";
;
CDS_LIB"mstr_standard"
BODY_TYPE"PLUMBING"
HDL_TAP"TRUE";
"B \NAC \NWC"4;
"S \NAC"
BN"0"89;
%"TAP"
"6","(-5625,1250)","0","mstr_standard","I43";
;
CDS_LIB"mstr_standard"
BODY_TYPE"PLUMBING"
HDL_TAP"TRUE";
"B \NAC \NWC"4;
"S \NAC"
BN"1"87;
%"TAP"
"6","(-5625,1450)","0","mstr_standard","I44";
;
CDS_LIB"mstr_standard"
BODY_TYPE"PLUMBING"
HDL_TAP"TRUE";
"B \NAC \NWC"4;
"S \NAC"
BN"3"83;
%"TAP"
"6","(-5625,1350)","0","mstr_standard","I45";
;
CDS_LIB"mstr_standard"
BODY_TYPE"PLUMBING"
HDL_TAP"TRUE";
"B \NAC \NWC"4;
"S \NAC"
BN"2"85;
%"TAP"
"6","(-5625,1550)","0","mstr_standard","I46";
;
CDS_LIB"mstr_standard"
BODY_TYPE"PLUMBING"
HDL_TAP"TRUE";
"B \NAC \NWC"4;
"S \NAC"
BN"4"81;
%"TAP"
"6","(-5625,1650)","0","mstr_standard","I47";
;
CDS_LIB"mstr_standard"
BODY_TYPE"PLUMBING"
HDL_TAP"TRUE";
"B \NAC \NWC"4;
"S \NAC"
BN"5"79;
%"TAP"
"6","(-5625,1750)","0","mstr_standard","I48";
;
CDS_LIB"mstr_standard"
BODY_TYPE"PLUMBING"
HDL_TAP"TRUE";
"B \NAC \NWC"4;
"S \NAC"
BN"6"77;
%"TAP"
"6","(-5625,1850)","0","mstr_standard","I50";
;
CDS_LIB"mstr_standard"
BODY_TYPE"PLUMBING"
HDL_TAP"TRUE";
"B \NAC \NWC"4;
"S \NAC"
BN"7"75;
%"TAP"
"6","(-5500,1200)","0","mstr_standard","I58";
;
CDS_LIB"mstr_standard"
BODY_TYPE"PLUMBING"
HDL_TAP"TRUE";
"B \NAC \NWC"5;
"S \NAC"
BN"0"88;
%"TAP"
"6","(-5500,1300)","0","mstr_standard","I59";
;
CDS_LIB"mstr_standard"
BODY_TYPE"PLUMBING"
HDL_TAP"TRUE";
"B \NAC \NWC"5;
"S \NAC"
BN"1"86;
%"TAP"
"6","(-5500,1400)","0","mstr_standard","I60";
;
CDS_LIB"mstr_standard"
BODY_TYPE"PLUMBING"
HDL_TAP"TRUE";
"B \NAC \NWC"5;
"S \NAC"
BN"2"84;
%"TAP"
"6","(-5500,1500)","0","mstr_standard","I61";
;
CDS_LIB"mstr_standard"
BODY_TYPE"PLUMBING"
HDL_TAP"TRUE";
"B \NAC \NWC"5;
"S \NAC"
BN"3"82;
%"TAP"
"6","(-5500,1700)","0","mstr_standard","I62";
;
CDS_LIB"mstr_standard"
BODY_TYPE"PLUMBING"
HDL_TAP"TRUE";
"B \NAC \NWC"5;
"S \NAC"
BN"5"78;
%"TAP"
"6","(-5500,1600)","0","mstr_standard","I63";
;
CDS_LIB"mstr_standard"
BODY_TYPE"PLUMBING"
HDL_TAP"TRUE";
"B \NAC \NWC"5;
"S \NAC"
BN"4"80;
%"TAP"
"6","(-5500,1800)","0","mstr_standard","I64";
;
CDS_LIB"mstr_standard"
BODY_TYPE"PLUMBING"
HDL_TAP"TRUE";
"B \NAC \NWC"5;
"S \NAC"
BN"6"76;
%"TAP"
"6","(-5500,1900)","0","mstr_standard","I65";
;
CDS_LIB"mstr_standard"
BODY_TYPE"PLUMBING"
HDL_TAP"TRUE";
"B \NAC \NWC"5;
"S \NAC"
BN"7"74;
%"TAP"
"1","(-2725,1200)","0","mstr_standard","I74";
;
CDS_LIB"mstr_standard"
BODY_TYPE"PLUMBING"
HDL_TAP"TRUE";
"B \NAC \NWC"10;
"S \NAC"
BN"0"51;
%"TAP"
"1","(-2725,1300)","0","mstr_standard","I75";
;
CDS_LIB"mstr_standard"
BODY_TYPE"PLUMBING"
HDL_TAP"TRUE";
"B \NAC \NWC"10;
"S \NAC"
BN"1"49;
%"TAP"
"1","(-2725,1400)","0","mstr_standard","I76";
;
CDS_LIB"mstr_standard"
BODY_TYPE"PLUMBING"
HDL_TAP"TRUE";
"B \NAC \NWC"10;
"S \NAC"
BN"2"47;
%"TAP"
"1","(-2725,1500)","0","mstr_standard","I77";
;
CDS_LIB"mstr_standard"
BODY_TYPE"PLUMBING"
HDL_TAP"TRUE";
"B \NAC \NWC"10;
"S \NAC"
BN"3"45;
%"TAP"
"1","(-2725,1600)","0","mstr_standard","I78";
;
CDS_LIB"mstr_standard"
BODY_TYPE"PLUMBING"
HDL_TAP"TRUE";
"B \NAC \NWC"10;
"S \NAC"
BN"4"43;
%"TAP"
"1","(-2600,1250)","0","mstr_standard","I79";
;
CDS_LIB"mstr_standard"
BODY_TYPE"PLUMBING"
HDL_TAP"TRUE";
"B \NAC \NWC"9;
"S \NAC"
BN"1"50;
%"TAP"
"1","(-2600,1150)","0","mstr_standard","I80";
;
CDS_LIB"mstr_standard"
BODY_TYPE"PLUMBING"
HDL_TAP"TRUE";
"B \NAC \NWC"9;
"S \NAC"
BN"0"52;
%"TAP"
"1","(-2600,1350)","0","mstr_standard","I81";
;
CDS_LIB"mstr_standard"
BODY_TYPE"PLUMBING"
HDL_TAP"TRUE";
"B \NAC \NWC"9;
"S \NAC"
BN"2"48;
%"TAP"
"1","(-2600,1450)","0","mstr_standard","I82";
;
CDS_LIB"mstr_standard"
BODY_TYPE"PLUMBING"
HDL_TAP"TRUE";
"B \NAC \NWC"9;
"S \NAC"
BN"3"46;
%"TAP"
"1","(-2600,1650)","0","mstr_standard","I83";
;
CDS_LIB"mstr_standard"
BODY_TYPE"PLUMBING"
HDL_TAP"TRUE";
"B \NAC \NWC"9;
"S \NAC"
BN"5"42;
%"TAP"
"1","(-2600,1550)","0","mstr_standard","I84";
;
CDS_LIB"mstr_standard"
BODY_TYPE"PLUMBING"
HDL_TAP"TRUE";
"B \NAC \NWC"9;
"S \NAC"
BN"4"44;
%"TAP"
"1","(-2725,1700)","0","mstr_standard","I85";
;
CDS_LIB"mstr_standard"
BODY_TYPE"PLUMBING"
HDL_TAP"TRUE";
"B \NAC \NWC"10;
"S \NAC"
BN"5"41;
%"TAP"
"1","(-2725,1800)","0","mstr_standard","I86";
;
CDS_LIB"mstr_standard"
BODY_TYPE"PLUMBING"
HDL_TAP"TRUE";
"B \NAC \NWC"10;
"S \NAC"
BN"6"39;
%"TAP"
"1","(-2725,1900)","0","mstr_standard","I87";
;
CDS_LIB"mstr_standard"
BODY_TYPE"PLUMBING"
HDL_TAP"TRUE";
"B \NAC \NWC"10;
"S \NAC"
BN"7"37;
%"LBG_CORE_QAT_EXT_D"
"4","(-3925,2150)","0","mstr_u_proc","I9";
;
CDS_SEC"4"
LOCATION"U7C1"
PART_NUMBER"H91415-002"
MATERIAL"IC"
PACK_TYPE"BGA1"
SEC_TYPE"BGA1"
SEC"4"
CDS_LIB"mstr_u_proc"
BOM_COST"SB"
CDS_LOCATION"U7C1"
ROOM"SB";
"PCIEUP_9_TXP"
$PN"M66"15;
"PCIEUP_9_TXN"
$PN"J66"16;
"PCIEUP_9_RXP"
$PN"B58"53;
"PCIEUP_9_RXN"
$PN"D58"54;
"PCIEUP_8_TXP"
$PN"M63"35;
"PCIEUP_8_TXN"
$PN"K65"36;
"PCIEUP_8_RXP"
$PN"A57"72;
"PCIEUP_8_RXN"
$PN"C57"73;
"PCIEUP_7_TXP"
$PN"R61"37;
"PCIEUP_7_TXN"
$PN"P59"38;
"PCIEUP_7_RXP"
$PN"B55"74;
"PCIEUP_7_RXN"
$PN"D55"75;
"PCIEUP_6_TXP"
$PN"J63"39;
"PCIEUP_6_TXN"
$PN"H61"40;
"PCIEUP_6_RXP"
$PN"A54"76;
"PCIEUP_6_RXN"
$PN"C54"77;
"PCIEUP_5_TXP"
$PN"K61"41;
"PCIEUP_5_TXN"
$PN"N61"42;
"PCIEUP_5_RXP"
$PN"B53"78;
"PCIEUP_5_RXN"
$PN"D53"79;
"PCIEUP_4_TXP"
$PN"M59"43;
"PCIEUP_4_TXN"
$PN"N58"44;
"PCIEUP_4_RXP"
$PN"A52"80;
"PCIEUP_4_RXN"
$PN"C52"81;
"PCIEUP_3_TXP"
$PN"K58"45;
"PCIEUP_3_TXN"
$PN"J56"46;
"PCIEUP_3_RXP"
$PN"B51"82;
"PCIEUP_3_RXN"
$PN"D51"83;
"PCIEUP_2_TXP"
$PN"G56"47;
"PCIEUP_2_TXN"
$PN"H54"48;
"PCIEUP_2_RXP"
$PN"A50"84;
"PCIEUP_2_RXN"
$PN"C50"85;
"PCIEUP_1_TXP"
$PN"M56"49;
"PCIEUP_1_TXN"
$PN"P56"50;
"PCIEUP_1_RXP"
$PN"B49"86;
"PCIEUP_1_RXN"
$PN"D49"87;
"PCIEUP_15_TXP"
$PN"AA65"17;
"PCIEUP_15_TXN"
$PN"Y66"18;
"PCIEUP_15_RXP"
$PN"B64"55;
"PCIEUP_15_RXN"
$PN"D64"56;
"PCIEUP_14_TXP"
$PN"V63"19;
"PCIEUP_14_TXN"
$PN"W65"20;
"PCIEUP_14_RXP"
$PN"A63"57;
"PCIEUP_14_RXN"
$PN"C63"58;
"PCIEUP_13_TXP"
$PN"U61"21;
"PCIEUP_13_TXN"
$PN"T63"22;
"PCIEUP_13_RXP"
$PN"B62"59;
"PCIEUP_13_RXN"
$PN"D62"60;
"PCIEUP_12_TXP"
$PN"U65"23;
"PCIEUP_12_TXN"
$PN"R65"24;
"PCIEUP_12_RXP"
$PN"A61"61;
"PCIEUP_12_RXN"
$PN"C61"62;
"PCIEUP_11_TXP"
$PN"V59"25;
"PCIEUP_11_TXN"
$PN"T59"26;
"PCIEUP_11_RXP"
$PN"B60"63;
"PCIEUP_11_RXN"
$PN"D60"64;
"PCIEUP_10_TXP"
$PN"P66"27;
"PCIEUP_10_TXN"
$PN"N65"28;
"PCIEUP_10_RXP"
$PN"A59"65;
"PCIEUP_10_RXN"
$PN"C59"66;
"PCIEUP_0_TXP"
$PN"G52"51;
"PCIEUP_0_TXN"
$PN"J52"52;
"PCIEUP_0_RXP"
$PN"A48"88;
"PCIEUP_0_RXN"
$PN"C48"89;
"DMI_TXP<0>"
$PN"K46"90;
"DMI_TXP<1>"
$PN"H50"29;
"DMI_TXP<2>"
$PN"M52"30;
"DMI_TXP<3>"
$PN"N54"31;
"DMI_TXN<0>"
$PN"H46"32;
"DMI_TXN<1>"
$PN"J48"33;
"DMI_TXN<2>"
$PN"K50"34;
"DMI_TXN<3>"
$PN"P52"91;
"DMI_RXP<0>"
$PN"B42"67;
"DMI_RXP<1>"
$PN"A43"92;
"DMI_RXP<2>"
$PN"B44"68;
"DMI_RXP<3>"
$PN"A45"69;
"DMI_RXN<0>"
$PN"D42"70;
"DMI_RXN<1>"
$PN"C43"13;
"DMI_RXN<2>"
$PN"D44"14;
"DMI_RXN<3>"
$PN"C45"71;
%"TAP"
"1","(-2600,1750)","0","mstr_standard","I90";
;
CDS_LIB"mstr_standard"
BODY_TYPE"PLUMBING"
HDL_TAP"TRUE";
"B \NAC \NWC"9;
"S \NAC"
BN"6"40;
%"TAP"
"1","(-2600,1850)","0","mstr_standard","I91";
;
CDS_LIB"mstr_standard"
BODY_TYPE"PLUMBING"
HDL_TAP"TRUE";
"B \NAC \NWC"9;
"S \NAC"
BN"7"38;
%"TAP"
"6","(-5500,2000)","0","mstr_standard","I97";
;
CDS_LIB"mstr_standard"
BODY_TYPE"PLUMBING"
HDL_TAP"TRUE";
"B \NAC \NWC"7;
"S \NAC"
BN"8"72;
%"TAP"
"6","(-5500,2100)","0","mstr_standard","I98";
;
CDS_LIB"mstr_standard"
BODY_TYPE"PLUMBING"
HDL_TAP"TRUE";
"B \NAC \NWC"7;
"S \NAC"
BN"9"53;
%"TAP"
"6","(-5500,2200)","0","mstr_standard","I99";
;
CDS_LIB"mstr_standard"
BODY_TYPE"PLUMBING"
HDL_TAP"TRUE";
"B \NAC \NWC"7;
"S \NAC"
BN"10"65;
END.
